(kicad_pcb
	(version 20260206)
	(generator "pcbnew")
	(generator_version "10.0")
	(general
		(thickness 1.6)
		(legacy_teardrops no)
	)
	(paper "A4")
	(title_block
		(title "01162023_DA0F0TEBIF0_F0T_Expander_BD_F_brd_V02_OCP.brd")
		(comment 1 "Grand Teton / footprints 1981-1986 of 9728")
	)
	(layers
		(0 "F.Cu" signal "TOP")
		(4 "In1.Cu" signal "GND")
		(6 "In2.Cu" signal "VCC")
		(8 "In3.Cu" signal "VCC1")
		(10 "In4.Cu" signal "GND1")
		(12 "In5.Cu" signal "IN1")
		(14 "In6.Cu" signal "GND2")
		(16 "In7.Cu" signal "IN2")
		(18 "In8.Cu" signal "GND3")
		(20 "In9.Cu" signal "IN3")
		(22 "In10.Cu" signal "GND4")
		(24 "In11.Cu" signal "IN4")
		(26 "In12.Cu" signal "GND5")
		(28 "In13.Cu" signal "IN5")
		(30 "In14.Cu" signal "GND6")
		(32 "In15.Cu" signal "IN6")
		(34 "In16.Cu" signal "GND7")
		(2 "B.Cu" signal "BOTTOM")
		(9 "F.Adhes" user "F.Adhesive")
		(11 "B.Adhes" user "B.Adhesive")
		(13 "F.Paste" user "Package Geometry/Pastemask Top")
		(15 "B.Paste" user "Package Geometry/Pastemask Bottom")
		(5 "F.SilkS" user "Ref Des/Silkscreen Top")
		(7 "B.SilkS" user "Ref Des/Silkscreen Bottom")
		(1 "F.Mask" user "Board Geometry/Soldermask Top")
		(3 "B.Mask" user "Board Geometry/Soldermask Bottom")
		(17 "Dwgs.User" user "User.Drawings")
		(19 "Cmts.User" user "User.Comments")
		(21 "Eco1.User" user "User.Eco1")
		(23 "Eco2.User" user "User.Eco2")
		(25 "Edge.Cuts" user "Board Geometry/Outline")
		(27 "Margin" user)
		(31 "F.CrtYd" user "Package Geometry/Place Bound Top")
		(29 "B.CrtYd" user "Package Geometry/Place Bound Bottom")
		(35 "F.Fab" user "Ref Des/Assembly Top")
		(33 "B.Fab" user "Ref Des/Assembly Bottom")
	)
	(footprint ""
		(layer "F.Cu")
		(at 262.281924 -283.389832 180)
		(property "Reference" "C3410"
			(at 0 0 180)
			(layer "F.SilkS")
			(hide yes)
			(effects
				(font
					(size 1.27 1.27)
				)
			)
		)
		(property "Value" ""
			(at 0 0 180)
			(layer "F.Fab")
			(effects
				(font
					(size 1.27 1.27)
				)
			)
		)
		(duplicate_pad_numbers_are_jumpers no)
		(fp_line
			(start 1.2954 0.5842)
			(end -1.2954 0.5842)
			(stroke
				(width 0.1524)
				(type default)
			)
			(layer "F.SilkS")
		)
		(fp_line
			(start 1.2954 -0.5842)
			(end 1.2954 0.5842)
			(stroke
				(width 0.1524)
				(type default)
			)
			(layer "F.SilkS")
		)
		(fp_line
			(start -1.2954 0.5842)
			(end -1.2954 -0.5842)
			(stroke
				(width 0.1524)
				(type default)
			)
			(layer "F.SilkS")
		)
		(fp_line
			(start -1.2954 -0.5842)
			(end 1.2954 -0.5842)
			(stroke
				(width 0.1524)
				(type default)
			)
			(layer "F.SilkS")
		)
		(fp_line
			(start 1.1938 0.4064)
			(end 0.8636 0.4064)
			(stroke
				(width 0.1)
				(type default)
			)
			(layer "F.Fab")
		)
		(fp_line
			(start 1.1938 -0.4064)
			(end 1.1938 0.4064)
			(stroke
				(width 0.1)
				(type default)
			)
			(layer "F.Fab")
		)
		(fp_line
			(start 0.8636 0.4572)
			(end -0.8636 0.4572)
			(stroke
				(width 0.1)
				(type default)
			)
			(layer "F.Fab")
		)
		(fp_line
			(start 0.8636 0.4064)
			(end 0.8636 0.4572)
			(stroke
				(width 0.1)
				(type default)
			)
			(layer "F.Fab")
		)
		(fp_line
			(start 0.8636 -0.4064)
			(end 1.1938 -0.4064)
			(stroke
				(width 0.1)
				(type default)
			)
			(layer "F.Fab")
		)
		(fp_line
			(start 0.8636 -0.4572)
			(end 0.8636 -0.4064)
			(stroke
				(width 0.1)
				(type default)
			)
			(layer "F.Fab")
		)
		(fp_line
			(start -0.8636 0.4572)
			(end -0.8636 0.4064)
			(stroke
				(width 0.1)
				(type default)
			)
			(layer "F.Fab")
		)
		(fp_line
			(start -0.8636 0.4064)
			(end -1.1938 0.4064)
			(stroke
				(width 0.1)
				(type default)
			)
			(layer "F.Fab")
		)
		(fp_line
			(start -0.8636 -0.4064)
			(end -0.8636 -0.4572)
			(stroke
				(width 0.1)
				(type default)
			)
			(layer "F.Fab")
		)
		(fp_line
			(start -0.8636 -0.4572)
			(end 0.8636 -0.4572)
			(stroke
				(width 0.1)
				(type default)
			)
			(layer "F.Fab")
		)
		(fp_line
			(start -1.1938 0.4064)
			(end -1.1938 -0.4064)
			(stroke
				(width 0.1)
				(type default)
			)
			(layer "F.Fab")
		)
		(fp_line
			(start -1.1938 -0.4064)
			(end -0.8636 -0.4064)
			(stroke
				(width 0.1)
				(type default)
			)
			(layer "F.Fab")
		)
		(pad "1" smd rect
			(at -0.7366 0 90)
			(size 0.7112 0.8128)
			(layers "F.Cu" "F.Mask" "F.Paste")
			(net "PCEPLL7_VDDA18_PEX2_R")
		)
		(pad "2" smd rect
			(at 0.7366 0 90)
			(size 0.7112 0.8128)
			(layers "F.Cu" "F.Mask" "F.Paste")
			(net "GND")
		)
	)
	(footprint ""
		(layer "F.Cu")
		(at 175.0949 -103.814372 180)
		(property "Reference" "R171"
			(at 0 0 180)
			(layer "F.SilkS")
			(hide yes)
			(effects
				(font
					(size 1.27 1.27)
				)
			)
		)
		(property "Value" ""
			(at 0 0 180)
			(layer "F.Fab")
			(effects
				(font
					(size 1.27 1.27)
				)
			)
		)
		(duplicate_pad_numbers_are_jumpers no)
		(fp_line
			(start 0.7874 0.4064)
			(end -0.7874 0.4064)
			(stroke
				(width 0.1524)
				(type default)
			)
			(layer "F.SilkS")
		)
		(fp_line
			(start 0.7874 -0.4064)
			(end 0.7874 0.4064)
			(stroke
				(width 0.1524)
				(type default)
			)
			(layer "F.SilkS")
		)
		(fp_line
			(start -0.7874 0.4064)
			(end -0.7874 -0.4064)
			(stroke
				(width 0.1524)
				(type default)
			)
			(layer "F.SilkS")
		)
		(fp_line
			(start -0.7874 -0.4064)
			(end 0.7874 -0.4064)
			(stroke
				(width 0.1524)
				(type default)
			)
			(layer "F.SilkS")
		)
		(fp_line
			(start 0.67945 0.3048)
			(end 0.120396 0.3048)
			(stroke
				(width 0.1)
				(type default)
			)
			(layer "F.Fab")
		)
		(fp_line
			(start 0.67945 -0.3048)
			(end 0.67945 0.3048)
			(stroke
				(width 0.1)
				(type default)
			)
			(layer "F.Fab")
		)
		(fp_line
			(start 0.12065 -0.2794)
			(end 0.12065 -0.3048)
			(stroke
				(width 0.1)
				(type default)
			)
			(layer "F.Fab")
		)
		(fp_line
			(start 0.12065 -0.3048)
			(end 0.67945 -0.3048)
			(stroke
				(width 0.1)
				(type default)
			)
			(layer "F.Fab")
		)
		(fp_line
			(start 0.120396 0.3048)
			(end 0.120396 0.2794)
			(stroke
				(width 0.1)
				(type default)
			)
			(layer "F.Fab")
		)
		(fp_line
			(start 0.120396 0.2794)
			(end -0.12065 0.2794)
			(stroke
				(width 0.1)
				(type default)
			)
			(layer "F.Fab")
		)
		(fp_line
			(start -0.12065 0.3048)
			(end -0.67945 0.3048)
			(stroke
				(width 0.1)
				(type default)
			)
			(layer "F.Fab")
		)
		(fp_line
			(start -0.12065 0.2794)
			(end -0.12065 0.3048)
			(stroke
				(width 0.1)
				(type default)
			)
			(layer "F.Fab")
		)
		(fp_line
			(start -0.12065 -0.2794)
			(end 0.12065 -0.2794)
			(stroke
				(width 0.1)
				(type default)
			)
			(layer "F.Fab")
		)
		(fp_line
			(start -0.12065 -0.305054)
			(end -0.12065 -0.2794)
			(stroke
				(width 0.1)
				(type default)
			)
			(layer "F.Fab")
		)
		(fp_line
			(start -0.67945 0.3048)
			(end -0.67945 -0.305054)
			(stroke
				(width 0.1)
				(type default)
			)
			(layer "F.Fab")
		)
		(fp_line
			(start -0.67945 -0.305054)
			(end -0.12065 -0.305054)
			(stroke
				(width 0.1)
				(type default)
			)
			(layer "F.Fab")
		)
		(pad "1" smd circle
			(at -0.40005 0 180)
			(size 0 0)
			(layers "F.Cu" "F.Mask" "F.Paste")
			(net "NCSI_NIC3_TXD0")
		)
		(pad "2" smd circle
			(at 0.40005 0 180)
			(size 0 0)
			(layers "F.Cu" "F.Mask" "F.Paste")
			(net "GND")
		)
	)
	(footprint ""
		(layer "F.Cu")
		(at 240.679224 -178.72075 90)
		(property "Reference" "R5479"
			(at 0 0 90)
			(layer "F.SilkS")
			(hide yes)
			(effects
				(font
					(size 1.27 1.27)
				)
			)
		)
		(property "Value" ""
			(at 0 0 90)
			(layer "F.Fab")
			(effects
				(font
					(size 1.27 1.27)
				)
			)
		)
		(duplicate_pad_numbers_are_jumpers no)
		(fp_line
			(start 0.7874 -0.4064)
			(end 0.7874 0.4064)
			(stroke
				(width 0.1524)
				(type default)
			)
			(layer "F.SilkS")
		)
		(fp_line
			(start -0.7874 -0.4064)
			(end 0.7874 -0.4064)
			(stroke
				(width 0.1524)
				(type default)
			)
			(layer "F.SilkS")
		)
		(fp_line
			(start 0.7874 0.4064)
			(end -0.7874 0.4064)
			(stroke
				(width 0.1524)
				(type default)
			)
			(layer "F.SilkS")
		)
		(fp_line
			(start -0.7874 0.4064)
			(end -0.7874 -0.4064)
			(stroke
				(width 0.1524)
				(type default)
			)
			(layer "F.SilkS")
		)
		(fp_line
			(start -0.12065 -0.305054)
			(end -0.12065 -0.2794)
			(stroke
				(width 0.1)
				(type default)
			)
			(layer "F.Fab")
		)
		(fp_line
			(start -0.67945 -0.305054)
			(end -0.12065 -0.305054)
			(stroke
				(width 0.1)
				(type default)
			)
			(layer "F.Fab")
		)
		(fp_line
			(start 0.67945 -0.3048)
			(end 0.67945 0.3048)
			(stroke
				(width 0.1)
				(type default)
			)
			(layer "F.Fab")
		)
		(fp_line
			(start 0.12065 -0.3048)
			(end 0.67945 -0.3048)
			(stroke
				(width 0.1)
				(type default)
			)
			(layer "F.Fab")
		)
		(fp_line
			(start 0.12065 -0.2794)
			(end 0.12065 -0.3048)
			(stroke
				(width 0.1)
				(type default)
			)
			(layer "F.Fab")
		)
		(fp_line
			(start -0.12065 -0.2794)
			(end 0.12065 -0.2794)
			(stroke
				(width 0.1)
				(type default)
			)
			(layer "F.Fab")
		)
		(fp_line
			(start 0.120396 0.2794)
			(end -0.12065 0.2794)
			(stroke
				(width 0.1)
				(type default)
			)
			(layer "F.Fab")
		)
		(fp_line
			(start -0.12065 0.2794)
			(end -0.12065 0.3048)
			(stroke
				(width 0.1)
				(type default)
			)
			(layer "F.Fab")
		)
		(fp_line
			(start 0.67945 0.3048)
			(end 0.120396 0.3048)
			(stroke
				(width 0.1)
				(type default)
			)
			(layer "F.Fab")
		)
		(fp_line
			(start 0.120396 0.3048)
			(end 0.120396 0.2794)
			(stroke
				(width 0.1)
				(type default)
			)
			(layer "F.Fab")
		)
		(fp_line
			(start -0.12065 0.3048)
			(end -0.67945 0.3048)
			(stroke
				(width 0.1)
				(type default)
			)
			(layer "F.Fab")
		)
		(fp_line
			(start -0.67945 0.3048)
			(end -0.67945 -0.305054)
			(stroke
				(width 0.1)
				(type default)
			)
			(layer "F.Fab")
		)
		(pad "1" smd circle
			(at -0.40005 0 90)
			(size 0 0)
			(layers "F.Cu" "F.Mask" "F.Paste")
			(net "P3V3_AUX")
		)
		(pad "2" smd circle
			(at 0.40005 0 90)
			(size 0 0)
			(layers "F.Cu" "F.Mask" "F.Paste")
			(net "BIC_RST_RSMRST_N")
		)
	)
	(footprint ""
		(layer "F.Cu")
		(at 187.946792 -343.952322 90)
		(property "Reference" "C379"
			(at 0 0 90)
			(layer "F.SilkS")
			(hide yes)
			(effects
				(font
					(size 1.27 1.27)
				)
			)
		)
		(property "Value" ""
			(at 0 0 90)
			(layer "F.Fab")
			(effects
				(font
					(size 1.27 1.27)
				)
			)
		)
		(duplicate_pad_numbers_are_jumpers no)
		(fp_line
			(start 0.299974 -0.150114)
			(end 0.299974 0.150114)
			(stroke
				(width 0.1)
				(type default)
			)
			(layer "F.Fab")
		)
		(fp_line
			(start -0.299974 -0.150114)
			(end 0.299974 -0.150114)
			(stroke
				(width 0.1)
				(type default)
			)
			(layer "F.Fab")
		)
		(fp_line
			(start 0.299974 0.150114)
			(end -0.299974 0.150114)
			(stroke
				(width 0.1)
				(type default)
			)
			(layer "F.Fab")
		)
		(fp_line
			(start -0.299974 0.150114)
			(end -0.299974 -0.150114)
			(stroke
				(width 0.1)
				(type default)
			)
			(layer "F.Fab")
		)
		(pad "1" smd rect
			(at -0.2667 0 90)
			(size 0.3048 0.381)
			(layers "F.Cu" "F.Mask" "F.Paste")
			(net "P5E_PEX1_STN7_TX_DN<124>")
		)
		(pad "2" smd rect
			(at 0.2667 0 90)
			(size 0.3048 0.381)
			(layers "F.Cu" "F.Mask" "F.Paste")
			(net "P5E_PEX1_STN7_TX_C_DN<124>")
		)
	)
	(footprint ""
		(layer "F.Cu")
		(at 368.975132 -56.977534 180)
		(property "Reference" "PC412"
			(at 0 0 180)
			(layer "F.SilkS")
			(hide yes)
			(effects
				(font
					(size 1.27 1.27)
				)
			)
		)
		(property "Value" ""
			(at 0 0 180)
			(layer "F.Fab")
			(effects
				(font
					(size 1.27 1.27)
				)
			)
		)
		(duplicate_pad_numbers_are_jumpers no)
		(fp_line
			(start 0.7874 0.4064)
			(end -0.7874 0.4064)
			(stroke
				(width 0.1524)
				(type default)
			)
			(layer "F.SilkS")
		)
		(fp_line
			(start 0.7874 -0.4064)
			(end 0.7874 0.4064)
			(stroke
				(width 0.1524)
				(type default)
			)
			(layer "F.SilkS")
		)
		(fp_line
			(start -0.7874 0.4064)
			(end -0.7874 -0.4064)
			(stroke
				(width 0.1524)
				(type default)
			)
			(layer "F.SilkS")
		)
		(fp_line
			(start -0.7874 -0.4064)
			(end 0.7874 -0.4064)
			(stroke
				(width 0.1524)
				(type default)
			)
			(layer "F.SilkS")
		)
		(fp_line
			(start 0.67945 0.3048)
			(end 0.120396 0.3048)
			(stroke
				(width 0.1)
				(type default)
			)
			(layer "F.Fab")
		)
		(fp_line
			(start 0.67945 -0.3048)
			(end 0.67945 0.3048)
			(stroke
				(width 0.1)
				(type default)
			)
			(layer "F.Fab")
		)
		(fp_line
			(start 0.12065 -0.2794)
			(end 0.12065 -0.3048)
			(stroke
				(width 0.1)
				(type default)
			)
			(layer "F.Fab")
		)
		(fp_line
			(start 0.12065 -0.3048)
			(end 0.67945 -0.3048)
			(stroke
				(width 0.1)
				(type default)
			)
			(layer "F.Fab")
		)
		(fp_line
			(start 0.120396 0.3048)
			(end 0.120396 0.2794)
			(stroke
				(width 0.1)
				(type default)
			)
			(layer "F.Fab")
		)
		(fp_line
			(start 0.120396 0.2794)
			(end -0.12065 0.2794)
			(stroke
				(width 0.1)
				(type default)
			)
			(layer "F.Fab")
		)
		(fp_line
			(start -0.12065 0.3048)
			(end -0.67945 0.3048)
			(stroke
				(width 0.1)
				(type default)
			)
			(layer "F.Fab")
		)
		(fp_line
			(start -0.12065 0.2794)
			(end -0.12065 0.3048)
			(stroke
				(width 0.1)
				(type default)
			)
			(layer "F.Fab")
		)
		(fp_line
			(start -0.12065 -0.2794)
			(end 0.12065 -0.2794)
			(stroke
				(width 0.1)
				(type default)
			)
			(layer "F.Fab")
		)
		(fp_line
			(start -0.12065 -0.305054)
			(end -0.12065 -0.2794)
			(stroke
				(width 0.1)
				(type default)
			)
			(layer "F.Fab")
		)
		(fp_line
			(start -0.67945 0.3048)
			(end -0.67945 -0.305054)
			(stroke
				(width 0.1)
				(type default)
			)
			(layer "F.Fab")
		)
		(fp_line
			(start -0.67945 -0.305054)
			(end -0.12065 -0.305054)
			(stroke
				(width 0.1)
				(type default)
			)
			(layer "F.Fab")
		)
		(pad "1" smd circle
			(at -0.40005 0 180)
			(size 0 0)
			(layers "F.Cu" "F.Mask" "F.Paste")
			(net "P12V_AUX")
		)
		(pad "2" smd circle
			(at 0.40005 0 180)
			(size 0 0)
			(layers "F.Cu" "F.Mask" "F.Paste")
			(net "GND")
		)
	)
	(footprint ""
		(layer "F.Cu")
		(at 124.149612 -159.844994 180)
		(property "Reference" "PR6893"
			(at 0 0 180)
			(layer "F.SilkS")
			(hide yes)
			(effects
				(font
					(size 1.27 1.27)
				)
			)
		)
		(property "Value" ""
			(at 0 0 180)
			(layer "F.Fab")
			(effects
				(font
					(size 1.27 1.27)
				)
			)
		)
		(duplicate_pad_numbers_are_jumpers no)
		(fp_line
			(start 0.7874 0.4064)
			(end -0.7874 0.4064)
			(stroke
				(width 0.1524)
				(type default)
			)
			(layer "F.SilkS")
		)
		(fp_line
			(start 0.7874 -0.4064)
			(end 0.7874 0.4064)
			(stroke
				(width 0.1524)
				(type default)
			)
			(layer "F.SilkS")
		)
		(fp_line
			(start -0.7874 0.4064)
			(end -0.7874 -0.4064)
			(stroke
				(width 0.1524)
				(type default)
			)
			(layer "F.SilkS")
		)
		(fp_line
			(start -0.7874 -0.4064)
			(end 0.7874 -0.4064)
			(stroke
				(width 0.1524)
				(type default)
			)
			(layer "F.SilkS")
		)
		(fp_line
			(start 0.67945 0.3048)
			(end 0.120396 0.3048)
			(stroke
				(width 0.1)
				(type default)
			)
			(layer "F.Fab")
		)
		(fp_line
			(start 0.67945 -0.3048)
			(end 0.67945 0.3048)
			(stroke
				(width 0.1)
				(type default)
			)
			(layer "F.Fab")
		)
		(fp_line
			(start 0.12065 -0.2794)
			(end 0.12065 -0.3048)
			(stroke
				(width 0.1)
				(type default)
			)
			(layer "F.Fab")
		)
		(fp_line
			(start 0.12065 -0.3048)
			(end 0.67945 -0.3048)
			(stroke
				(width 0.1)
				(type default)
			)
			(layer "F.Fab")
		)
		(fp_line
			(start 0.120396 0.3048)
			(end 0.120396 0.2794)
			(stroke
				(width 0.1)
				(type default)
			)
			(layer "F.Fab")
		)
		(fp_line
			(start 0.120396 0.2794)
			(end -0.12065 0.2794)
			(stroke
				(width 0.1)
				(type default)
			)
			(layer "F.Fab")
		)
		(fp_line
			(start -0.12065 0.3048)
			(end -0.67945 0.3048)
			(stroke
				(width 0.1)
				(type default)
			)
			(layer "F.Fab")
		)
		(fp_line
			(start -0.12065 0.2794)
			(end -0.12065 0.3048)
			(stroke
				(width 0.1)
				(type default)
			)
			(layer "F.Fab")
		)
		(fp_line
			(start -0.12065 -0.2794)
			(end 0.12065 -0.2794)
			(stroke
				(width 0.1)
				(type default)
			)
			(layer "F.Fab")
		)
		(fp_line
			(start -0.12065 -0.305054)
			(end -0.12065 -0.2794)
			(stroke
				(width 0.1)
				(type default)
			)
			(layer "F.Fab")
		)
		(fp_line
			(start -0.67945 0.3048)
			(end -0.67945 -0.305054)
			(stroke
				(width 0.1)
				(type default)
			)
			(layer "F.Fab")
		)
		(fp_line
			(start -0.67945 -0.305054)
			(end -0.12065 -0.305054)
			(stroke
				(width 0.1)
				(type default)
			)
			(layer "F.Fab")
		)
		(pad "1" smd circle
			(at -0.40005 0 180)
			(size 0 0)
			(layers "F.Cu" "F.Mask" "F.Paste")
			(net "P12V_NIC2_CO_FLTB")
		)
		(pad "2" smd circle
			(at 0.40005 0 180)
			(size 0 0)
			(layers "F.Cu" "F.Mask" "F.Paste")
			(net "P3V3_AUX")
		)
	)
)
